(kicad_pcb
	(version 20260206)
	(generator "pcbnew")
	(generator_version "10.0")
	(general
		(thickness 1.6)
		(legacy_teardrops no)
	)
	(paper "A4")
	(title_block
		(title "04192023_DAF0TMB3IC0_F0TG_MB_C_brd_V02_OCP.brd")
		(comment 1 "Grand Teton / footprints 1225-1230 of 8354")
	)
	(layers
		(0 "F.Cu" signal "TOP")
		(4 "In1.Cu" signal "GND")
		(6 "In2.Cu" signal "IN1")
		(8 "In3.Cu" signal "GND1")
		(10 "In4.Cu" signal "IN2")
		(12 "In5.Cu" signal "GND2")
		(14 "In6.Cu" signal "IN3")
		(16 "In7.Cu" signal "GND3")
		(18 "In8.Cu" signal "VCC")
		(20 "In9.Cu" signal "VCC1")
		(22 "In10.Cu" signal "GND4")
		(24 "In11.Cu" signal "IN4")
		(26 "In12.Cu" signal "GND5")
		(28 "In13.Cu" signal "IN5")
		(30 "In14.Cu" signal "GND6")
		(32 "In15.Cu" signal "IN6")
		(34 "In16.Cu" signal "GND7")
		(2 "B.Cu" signal "BOTTOM")
		(9 "F.Adhes" user "F.Adhesive")
		(11 "B.Adhes" user "B.Adhesive")
		(13 "F.Paste" user "Package Geometry/Pastemask Top")
		(15 "B.Paste" user "Package Geometry/Pastemask Bottom")
		(5 "F.SilkS" user "Ref Des/Silkscreen Top")
		(7 "B.SilkS" user "Ref Des/Silkscreen Bottom")
		(1 "F.Mask" user "Board Geometry/Soldermask Top")
		(3 "B.Mask" user "Board Geometry/Soldermask Bottom")
		(17 "Dwgs.User" user "User.Drawings")
		(19 "Cmts.User" user "User.Comments")
		(21 "Eco1.User" user "User.Eco1")
		(23 "Eco2.User" user "User.Eco2")
		(25 "Edge.Cuts" user "Board Geometry/Outline")
		(27 "Margin" user)
		(31 "F.CrtYd" user "Package Geometry/Place Bound Top")
		(29 "B.CrtYd" user "Package Geometry/Place Bound Bottom")
		(35 "F.Fab" user "Ref Des/Assembly Top")
		(33 "B.Fab" user "Ref Des/Assembly Bottom")
	)
	(footprint ""
		(layer "F.Cu")
		(at 77.64399 -174.960534 -90)
		(property "Reference" "PC307"
			(at 0 0 270)
			(layer "F.SilkS")
			(hide yes)
			(effects
				(font
					(size 1.27 1.27)
				)
			)
		)
		(property "Value" ""
			(at 0 0 270)
			(layer "F.Fab")
			(effects
				(font
					(size 1.27 1.27)
				)
			)
		)
		(duplicate_pad_numbers_are_jumpers no)
		(fp_line
			(start -0.7874 0.4064)
			(end -0.7874 -0.4064)
			(stroke
				(width 0.1524)
				(type default)
			)
			(layer "F.SilkS")
		)
		(fp_line
			(start -0.324866 0.4064)
			(end -0.7874 0.4064)
			(stroke
				(width 0.1524)
				(type default)
			)
			(layer "F.SilkS")
		)
		(fp_line
			(start 0.7874 0.4064)
			(end 0.411734 0.4064)
			(stroke
				(width 0.1524)
				(type default)
			)
			(layer "F.SilkS")
		)
		(fp_line
			(start -0.7874 -0.4064)
			(end 0.7874 -0.4064)
			(stroke
				(width 0.1524)
				(type default)
			)
			(layer "F.SilkS")
		)
		(fp_line
			(start 0.7874 -0.4064)
			(end 0.7874 0.4064)
			(stroke
				(width 0.1524)
				(type default)
			)
			(layer "F.SilkS")
		)
		(fp_line
			(start -0.67945 0.3048)
			(end -0.67945 -0.305054)
			(stroke
				(width 0.1)
				(type default)
			)
			(layer "F.Fab")
		)
		(fp_line
			(start -0.12065 0.3048)
			(end -0.67945 0.3048)
			(stroke
				(width 0.1)
				(type default)
			)
			(layer "F.Fab")
		)
		(fp_line
			(start 0.120396 0.3048)
			(end 0.120396 0.2794)
			(stroke
				(width 0.1)
				(type default)
			)
			(layer "F.Fab")
		)
		(fp_line
			(start 0.67945 0.3048)
			(end 0.120396 0.3048)
			(stroke
				(width 0.1)
				(type default)
			)
			(layer "F.Fab")
		)
		(fp_line
			(start -0.12065 0.2794)
			(end -0.12065 0.3048)
			(stroke
				(width 0.1)
				(type default)
			)
			(layer "F.Fab")
		)
		(fp_line
			(start 0.120396 0.2794)
			(end -0.12065 0.2794)
			(stroke
				(width 0.1)
				(type default)
			)
			(layer "F.Fab")
		)
		(fp_line
			(start -0.12065 -0.2794)
			(end 0.12065 -0.2794)
			(stroke
				(width 0.1)
				(type default)
			)
			(layer "F.Fab")
		)
		(fp_line
			(start 0.12065 -0.2794)
			(end 0.12065 -0.3048)
			(stroke
				(width 0.1)
				(type default)
			)
			(layer "F.Fab")
		)
		(fp_line
			(start 0.12065 -0.3048)
			(end 0.67945 -0.3048)
			(stroke
				(width 0.1)
				(type default)
			)
			(layer "F.Fab")
		)
		(fp_line
			(start 0.67945 -0.3048)
			(end 0.67945 0.3048)
			(stroke
				(width 0.1)
				(type default)
			)
			(layer "F.Fab")
		)
		(fp_line
			(start -0.67945 -0.305054)
			(end -0.12065 -0.305054)
			(stroke
				(width 0.1)
				(type default)
			)
			(layer "F.Fab")
		)
		(fp_line
			(start -0.12065 -0.305054)
			(end -0.12065 -0.2794)
			(stroke
				(width 0.1)
				(type default)
			)
			(layer "F.Fab")
		)
		(pad "1" smd circle
			(at -0.40005 0 270)
			(size 0 0)
			(layers "F.Cu" "F.Mask" "F.Paste")
			(net "PVDDCR_CPU0_P1_VCC5")
		)
		(pad "2" smd circle
			(at 0.40005 0 270)
			(size 0 0)
			(layers "F.Cu" "F.Mask" "F.Paste")
			(net "GND")
		)
	)
	(footprint ""
		(layer "F.Cu")
		(at 370.969032 -35.037522 -90)
		(property "Reference" "C1352"
			(at 0 0 270)
			(layer "F.SilkS")
			(hide yes)
			(effects
				(font
					(size 1.27 1.27)
				)
			)
		)
		(property "Value" ""
			(at 0 0 270)
			(layer "F.Fab")
			(effects
				(font
					(size 1.27 1.27)
				)
			)
		)
		(duplicate_pad_numbers_are_jumpers no)
		(fp_line
			(start -0.7874 0.4064)
			(end -0.7874 -0.4064)
			(stroke
				(width 0.1524)
				(type default)
			)
			(layer "F.SilkS")
		)
		(fp_line
			(start 0.7874 0.4064)
			(end -0.7874 0.4064)
			(stroke
				(width 0.1524)
				(type default)
			)
			(layer "F.SilkS")
		)
		(fp_line
			(start -0.7874 -0.4064)
			(end 0.7874 -0.4064)
			(stroke
				(width 0.1524)
				(type default)
			)
			(layer "F.SilkS")
		)
		(fp_line
			(start 0.7874 -0.4064)
			(end 0.7874 0.4064)
			(stroke
				(width 0.1524)
				(type default)
			)
			(layer "F.SilkS")
		)
		(fp_line
			(start -0.67945 0.3048)
			(end -0.67945 -0.305054)
			(stroke
				(width 0.1)
				(type default)
			)
			(layer "F.Fab")
		)
		(fp_line
			(start -0.12065 0.3048)
			(end -0.67945 0.3048)
			(stroke
				(width 0.1)
				(type default)
			)
			(layer "F.Fab")
		)
		(fp_line
			(start 0.120396 0.3048)
			(end 0.120396 0.2794)
			(stroke
				(width 0.1)
				(type default)
			)
			(layer "F.Fab")
		)
		(fp_line
			(start 0.67945 0.3048)
			(end 0.120396 0.3048)
			(stroke
				(width 0.1)
				(type default)
			)
			(layer "F.Fab")
		)
		(fp_line
			(start -0.12065 0.2794)
			(end -0.12065 0.3048)
			(stroke
				(width 0.1)
				(type default)
			)
			(layer "F.Fab")
		)
		(fp_line
			(start 0.120396 0.2794)
			(end -0.12065 0.2794)
			(stroke
				(width 0.1)
				(type default)
			)
			(layer "F.Fab")
		)
		(fp_line
			(start -0.12065 -0.2794)
			(end 0.12065 -0.2794)
			(stroke
				(width 0.1)
				(type default)
			)
			(layer "F.Fab")
		)
		(fp_line
			(start 0.12065 -0.2794)
			(end 0.12065 -0.3048)
			(stroke
				(width 0.1)
				(type default)
			)
			(layer "F.Fab")
		)
		(fp_line
			(start 0.12065 -0.3048)
			(end 0.67945 -0.3048)
			(stroke
				(width 0.1)
				(type default)
			)
			(layer "F.Fab")
		)
		(fp_line
			(start 0.67945 -0.3048)
			(end 0.67945 0.3048)
			(stroke
				(width 0.1)
				(type default)
			)
			(layer "F.Fab")
		)
		(fp_line
			(start -0.67945 -0.305054)
			(end -0.12065 -0.305054)
			(stroke
				(width 0.1)
				(type default)
			)
			(layer "F.Fab")
		)
		(fp_line
			(start -0.12065 -0.305054)
			(end -0.12065 -0.2794)
			(stroke
				(width 0.1)
				(type default)
			)
			(layer "F.Fab")
		)
		(pad "1" smd circle
			(at -0.40005 0 270)
			(size 0 0)
			(layers "F.Cu" "F.Mask" "F.Paste")
			(net "PVDD18_S5_P0")
		)
		(pad "2" smd circle
			(at 0.40005 0 270)
			(size 0 0)
			(layers "F.Cu" "F.Mask" "F.Paste")
			(net "GND")
		)
	)
	(footprint ""
		(layer "F.Cu")
		(at 422.763696 -357.688134 -90)
		(property "Reference" "PR419"
			(at 0 0 270)
			(layer "F.SilkS")
			(hide yes)
			(effects
				(font
					(size 1.27 1.27)
				)
			)
		)
		(property "Value" ""
			(at 0 0 270)
			(layer "F.Fab")
			(effects
				(font
					(size 1.27 1.27)
				)
			)
		)
		(duplicate_pad_numbers_are_jumpers no)
		(fp_line
			(start -0.7874 0.4064)
			(end -0.7874 -0.4064)
			(stroke
				(width 0.1524)
				(type default)
			)
			(layer "F.SilkS")
		)
		(fp_line
			(start 0.7874 0.4064)
			(end -0.7874 0.4064)
			(stroke
				(width 0.1524)
				(type default)
			)
			(layer "F.SilkS")
		)
		(fp_line
			(start -0.7874 -0.4064)
			(end 0.7874 -0.4064)
			(stroke
				(width 0.1524)
				(type default)
			)
			(layer "F.SilkS")
		)
		(fp_line
			(start 0.7874 -0.4064)
			(end 0.7874 0.4064)
			(stroke
				(width 0.1524)
				(type default)
			)
			(layer "F.SilkS")
		)
		(fp_line
			(start -0.67945 0.3048)
			(end -0.67945 -0.305054)
			(stroke
				(width 0.1)
				(type default)
			)
			(layer "F.Fab")
		)
		(fp_line
			(start -0.12065 0.3048)
			(end -0.67945 0.3048)
			(stroke
				(width 0.1)
				(type default)
			)
			(layer "F.Fab")
		)
		(fp_line
			(start 0.120396 0.3048)
			(end 0.120396 0.2794)
			(stroke
				(width 0.1)
				(type default)
			)
			(layer "F.Fab")
		)
		(fp_line
			(start 0.67945 0.3048)
			(end 0.120396 0.3048)
			(stroke
				(width 0.1)
				(type default)
			)
			(layer "F.Fab")
		)
		(fp_line
			(start -0.12065 0.2794)
			(end -0.12065 0.3048)
			(stroke
				(width 0.1)
				(type default)
			)
			(layer "F.Fab")
		)
		(fp_line
			(start 0.120396 0.2794)
			(end -0.12065 0.2794)
			(stroke
				(width 0.1)
				(type default)
			)
			(layer "F.Fab")
		)
		(fp_line
			(start -0.12065 -0.2794)
			(end 0.12065 -0.2794)
			(stroke
				(width 0.1)
				(type default)
			)
			(layer "F.Fab")
		)
		(fp_line
			(start 0.12065 -0.2794)
			(end 0.12065 -0.3048)
			(stroke
				(width 0.1)
				(type default)
			)
			(layer "F.Fab")
		)
		(fp_line
			(start 0.12065 -0.3048)
			(end 0.67945 -0.3048)
			(stroke
				(width 0.1)
				(type default)
			)
			(layer "F.Fab")
		)
		(fp_line
			(start 0.67945 -0.3048)
			(end 0.67945 0.3048)
			(stroke
				(width 0.1)
				(type default)
			)
			(layer "F.Fab")
		)
		(fp_line
			(start -0.67945 -0.305054)
			(end -0.12065 -0.305054)
			(stroke
				(width 0.1)
				(type default)
			)
			(layer "F.Fab")
		)
		(fp_line
			(start -0.12065 -0.305054)
			(end -0.12065 -0.2794)
			(stroke
				(width 0.1)
				(type default)
			)
			(layer "F.Fab")
		)
		(pad "1" smd circle
			(at -0.40005 0 270)
			(size 0 0)
			(layers "F.Cu" "F.Mask" "F.Paste")
			(net "NC_PVDD11_S3_P0_IMON7")
		)
		(pad "2" smd circle
			(at 0.40005 0 270)
			(size 0 0)
			(layers "F.Cu" "F.Mask" "F.Paste")
			(net "GND")
		)
	)
	(footprint ""
		(layer "F.Cu")
		(at 105.485946 -54.882034 -90)
		(property "Reference" "R6315"
			(at 0 0 270)
			(layer "F.SilkS")
			(hide yes)
			(effects
				(font
					(size 1.27 1.27)
				)
			)
		)
		(property "Value" ""
			(at 0 0 270)
			(layer "F.Fab")
			(effects
				(font
					(size 1.27 1.27)
				)
			)
		)
		(duplicate_pad_numbers_are_jumpers no)
		(fp_line
			(start -0.7874 0.4064)
			(end -0.7874 -0.4064)
			(stroke
				(width 0.1524)
				(type default)
			)
			(layer "F.SilkS")
		)
		(fp_line
			(start 0.7874 0.4064)
			(end -0.7874 0.4064)
			(stroke
				(width 0.1524)
				(type default)
			)
			(layer "F.SilkS")
		)
		(fp_line
			(start -0.7874 -0.4064)
			(end 0.7874 -0.4064)
			(stroke
				(width 0.1524)
				(type default)
			)
			(layer "F.SilkS")
		)
		(fp_line
			(start 0.7874 -0.4064)
			(end 0.7874 0.4064)
			(stroke
				(width 0.1524)
				(type default)
			)
			(layer "F.SilkS")
		)
		(fp_line
			(start -0.67945 0.3048)
			(end -0.67945 -0.305054)
			(stroke
				(width 0.1)
				(type default)
			)
			(layer "F.Fab")
		)
		(fp_line
			(start -0.12065 0.3048)
			(end -0.67945 0.3048)
			(stroke
				(width 0.1)
				(type default)
			)
			(layer "F.Fab")
		)
		(fp_line
			(start 0.120396 0.3048)
			(end 0.120396 0.2794)
			(stroke
				(width 0.1)
				(type default)
			)
			(layer "F.Fab")
		)
		(fp_line
			(start 0.67945 0.3048)
			(end 0.120396 0.3048)
			(stroke
				(width 0.1)
				(type default)
			)
			(layer "F.Fab")
		)
		(fp_line
			(start -0.12065 0.2794)
			(end -0.12065 0.3048)
			(stroke
				(width 0.1)
				(type default)
			)
			(layer "F.Fab")
		)
		(fp_line
			(start 0.120396 0.2794)
			(end -0.12065 0.2794)
			(stroke
				(width 0.1)
				(type default)
			)
			(layer "F.Fab")
		)
		(fp_line
			(start -0.12065 -0.2794)
			(end 0.12065 -0.2794)
			(stroke
				(width 0.1)
				(type default)
			)
			(layer "F.Fab")
		)
		(fp_line
			(start 0.12065 -0.2794)
			(end 0.12065 -0.3048)
			(stroke
				(width 0.1)
				(type default)
			)
			(layer "F.Fab")
		)
		(fp_line
			(start 0.12065 -0.3048)
			(end 0.67945 -0.3048)
			(stroke
				(width 0.1)
				(type default)
			)
			(layer "F.Fab")
		)
		(fp_line
			(start 0.67945 -0.3048)
			(end 0.67945 0.3048)
			(stroke
				(width 0.1)
				(type default)
			)
			(layer "F.Fab")
		)
		(fp_line
			(start -0.67945 -0.305054)
			(end -0.12065 -0.305054)
			(stroke
				(width 0.1)
				(type default)
			)
			(layer "F.Fab")
		)
		(fp_line
			(start -0.12065 -0.305054)
			(end -0.12065 -0.2794)
			(stroke
				(width 0.1)
				(type default)
			)
			(layer "F.Fab")
		)
		(pad "1" smd circle
			(at -0.40005 0 270)
			(size 0 0)
			(layers "F.Cu" "F.Mask" "F.Paste")
			(net "P3V3_AUX")
		)
		(pad "2" smd circle
			(at 0.40005 0 270)
			(size 0 0)
			(layers "F.Cu" "F.Mask" "F.Paste")
			(net "USB_HUB2_TI_OVERCUR2")
		)
	)
	(footprint ""
		(layer "F.Cu")
		(at 264.986516 -138.321796 180)
		(property "Reference" "R1529"
			(at 0 0 180)
			(layer "F.SilkS")
			(hide yes)
			(effects
				(font
					(size 1.27 1.27)
				)
			)
		)
		(property "Value" ""
			(at 0 0 180)
			(layer "F.Fab")
			(effects
				(font
					(size 1.27 1.27)
				)
			)
		)
		(duplicate_pad_numbers_are_jumpers no)
		(fp_line
			(start 0.7874 0.4064)
			(end -0.7874 0.4064)
			(stroke
				(width 0.1524)
				(type default)
			)
			(layer "F.SilkS")
		)
		(fp_line
			(start 0.7874 -0.4064)
			(end 0.7874 0.4064)
			(stroke
				(width 0.1524)
				(type default)
			)
			(layer "F.SilkS")
		)
		(fp_line
			(start -0.7874 0.4064)
			(end -0.7874 -0.4064)
			(stroke
				(width 0.1524)
				(type default)
			)
			(layer "F.SilkS")
		)
		(fp_line
			(start -0.7874 -0.4064)
			(end 0.7874 -0.4064)
			(stroke
				(width 0.1524)
				(type default)
			)
			(layer "F.SilkS")
		)
		(fp_line
			(start 0.67945 0.3048)
			(end 0.120396 0.3048)
			(stroke
				(width 0.1)
				(type default)
			)
			(layer "F.Fab")
		)
		(fp_line
			(start 0.67945 -0.3048)
			(end 0.67945 0.3048)
			(stroke
				(width 0.1)
				(type default)
			)
			(layer "F.Fab")
		)
		(fp_line
			(start 0.12065 -0.2794)
			(end 0.12065 -0.3048)
			(stroke
				(width 0.1)
				(type default)
			)
			(layer "F.Fab")
		)
		(fp_line
			(start 0.12065 -0.3048)
			(end 0.67945 -0.3048)
			(stroke
				(width 0.1)
				(type default)
			)
			(layer "F.Fab")
		)
		(fp_line
			(start 0.120396 0.3048)
			(end 0.120396 0.2794)
			(stroke
				(width 0.1)
				(type default)
			)
			(layer "F.Fab")
		)
		(fp_line
			(start 0.120396 0.2794)
			(end -0.12065 0.2794)
			(stroke
				(width 0.1)
				(type default)
			)
			(layer "F.Fab")
		)
		(fp_line
			(start -0.12065 0.3048)
			(end -0.67945 0.3048)
			(stroke
				(width 0.1)
				(type default)
			)
			(layer "F.Fab")
		)
		(fp_line
			(start -0.12065 0.2794)
			(end -0.12065 0.3048)
			(stroke
				(width 0.1)
				(type default)
			)
			(layer "F.Fab")
		)
		(fp_line
			(start -0.12065 -0.2794)
			(end 0.12065 -0.2794)
			(stroke
				(width 0.1)
				(type default)
			)
			(layer "F.Fab")
		)
		(fp_line
			(start -0.12065 -0.305054)
			(end -0.12065 -0.2794)
			(stroke
				(width 0.1)
				(type default)
			)
			(layer "F.Fab")
		)
		(fp_line
			(start -0.67945 0.3048)
			(end -0.67945 -0.305054)
			(stroke
				(width 0.1)
				(type default)
			)
			(layer "F.Fab")
		)
		(fp_line
			(start -0.67945 -0.305054)
			(end -0.12065 -0.305054)
			(stroke
				(width 0.1)
				(type default)
			)
			(layer "F.Fab")
		)
		(pad "1" smd circle
			(at -0.40005 0 180)
			(size 0 0)
			(layers "F.Cu" "F.Mask" "F.Paste")
			(net "PVDD18_S5_P0")
		)
		(pad "2" smd circle
			(at 0.40005 0 180)
			(size 0 0)
			(layers "F.Cu" "F.Mask" "F.Paste")
			(net "SPI_CPU0_D3")
		)
	)
	(footprint ""
		(layer "F.Cu")
		(at 297.670982 -351.573846 90)
		(property "Reference" "PC145_7"
			(at 0 0 90)
			(layer "F.SilkS")
			(hide yes)
			(effects
				(font
					(size 1.27 1.27)
				)
			)
		)
		(property "Value" ""
			(at 0 0 90)
			(layer "F.Fab")
			(effects
				(font
					(size 1.27 1.27)
				)
			)
		)
		(duplicate_pad_numbers_are_jumpers no)
		(fp_line
			(start 0.7874 -0.4064)
			(end 0.7874 0.4064)
			(stroke
				(width 0.1524)
				(type default)
			)
			(layer "F.SilkS")
		)
		(fp_line
			(start -0.7874 -0.4064)
			(end 0.7874 -0.4064)
			(stroke
				(width 0.1524)
				(type default)
			)
			(layer "F.SilkS")
		)
		(fp_line
			(start 0.7874 0.4064)
			(end -0.7874 0.4064)
			(stroke
				(width 0.1524)
				(type default)
			)
			(layer "F.SilkS")
		)
		(fp_line
			(start -0.7874 0.4064)
			(end -0.7874 -0.4064)
			(stroke
				(width 0.1524)
				(type default)
			)
			(layer "F.SilkS")
		)
		(fp_line
			(start -0.12065 -0.305054)
			(end -0.12065 -0.2794)
			(stroke
				(width 0.1)
				(type default)
			)
			(layer "F.Fab")
		)
		(fp_line
			(start -0.67945 -0.305054)
			(end -0.12065 -0.305054)
			(stroke
				(width 0.1)
				(type default)
			)
			(layer "F.Fab")
		)
		(fp_line
			(start 0.67945 -0.3048)
			(end 0.67945 0.3048)
			(stroke
				(width 0.1)
				(type default)
			)
			(layer "F.Fab")
		)
		(fp_line
			(start 0.12065 -0.3048)
			(end 0.67945 -0.3048)
			(stroke
				(width 0.1)
				(type default)
			)
			(layer "F.Fab")
		)
		(fp_line
			(start 0.12065 -0.2794)
			(end 0.12065 -0.3048)
			(stroke
				(width 0.1)
				(type default)
			)
			(layer "F.Fab")
		)
		(fp_line
			(start -0.12065 -0.2794)
			(end 0.12065 -0.2794)
			(stroke
				(width 0.1)
				(type default)
			)
			(layer "F.Fab")
		)
		(fp_line
			(start 0.120396 0.2794)
			(end -0.12065 0.2794)
			(stroke
				(width 0.1)
				(type default)
			)
			(layer "F.Fab")
		)
		(fp_line
			(start -0.12065 0.2794)
			(end -0.12065 0.3048)
			(stroke
				(width 0.1)
				(type default)
			)
			(layer "F.Fab")
		)
		(fp_line
			(start 0.67945 0.3048)
			(end 0.120396 0.3048)
			(stroke
				(width 0.1)
				(type default)
			)
			(layer "F.Fab")
		)
		(fp_line
			(start 0.120396 0.3048)
			(end 0.120396 0.2794)
			(stroke
				(width 0.1)
				(type default)
			)
			(layer "F.Fab")
		)
		(fp_line
			(start -0.12065 0.3048)
			(end -0.67945 0.3048)
			(stroke
				(width 0.1)
				(type default)
			)
			(layer "F.Fab")
		)
		(fp_line
			(start -0.67945 0.3048)
			(end -0.67945 -0.305054)
			(stroke
				(width 0.1)
				(type default)
			)
			(layer "F.Fab")
		)
		(pad "1" smd circle
			(at -0.40005 0 90)
			(size 0 0)
			(layers "F.Cu" "F.Mask" "F.Paste")
			(net "PVDDCR_CPU1_P0_VCCS")
		)
		(pad "2" smd circle
			(at 0.40005 0 90)
			(size 0 0)
			(layers "F.Cu" "F.Mask" "F.Paste")
			(net "GND")
		)
	)
)
